(kicad_pcb
	(version 20260206)
	(generator "pcbnew")
	(generator_version "10.0")
	(general
		(thickness 1.6)
		(legacy_teardrops no)
	)
	(paper "A4")
	(title_block
		(title "03242023_DA0F0TMBIJ0_F0T_Motherboard_J_brd_V01_OCP.brd")
		(comment 1 "Grand Teton / footprint 1335 of 6105 (J17), pads 113-224 of 291")
	)
	(layers
		(0 "F.Cu" signal "TOP")
		(4 "In1.Cu" signal "GND")
		(6 "In2.Cu" signal "IN1")
		(8 "In3.Cu" signal "GND1")
		(10 "In4.Cu" signal "IN2")
		(12 "In5.Cu" signal "GND2")
		(14 "In6.Cu" signal "IN3")
		(16 "In7.Cu" signal "GND3")
		(18 "In8.Cu" signal "VCC")
		(20 "In9.Cu" signal "VCC1")
		(22 "In10.Cu" signal "GND4")
		(24 "In11.Cu" signal "IN4")
		(26 "In12.Cu" signal "GND5")
		(28 "In13.Cu" signal "IN5")
		(30 "In14.Cu" signal "GND6")
		(32 "In15.Cu" signal "IN6")
		(34 "In16.Cu" signal "GND7")
		(2 "B.Cu" signal "BOTTOM")
		(9 "F.Adhes" user "F.Adhesive")
		(11 "B.Adhes" user "B.Adhesive")
		(13 "F.Paste" user "Package Geometry/Pastemask Top")
		(15 "B.Paste" user "Package Geometry/Pastemask Bottom")
		(5 "F.SilkS" user "Ref Des/Silkscreen Top")
		(7 "B.SilkS" user "Ref Des/Silkscreen Bottom")
		(1 "F.Mask" user "Board Geometry/Soldermask Top")
		(3 "B.Mask" user "Board Geometry/Soldermask Bottom")
		(17 "Dwgs.User" user "User.Drawings")
		(19 "Cmts.User" user "User.Comments")
		(21 "Eco1.User" user "User.Eco1")
		(23 "Eco2.User" user "User.Eco2")
		(25 "Edge.Cuts" user "Board Geometry/Outline")
		(27 "Margin" user)
		(31 "F.CrtYd" user "Package Geometry/Place Bound Top")
		(29 "B.CrtYd" user "Package Geometry/Place Bound Bottom")
		(35 "F.Fab" user "Ref Des/Assembly Top")
		(33 "B.Fab" user "Ref Des/Assembly Bottom")
	)
	(footprint ""
		(layer "F.Cu")
		(at 55.45328 -258.091686)
		(property "Reference" "J17"
			(at -0.178562 -81.717134 0)
			(unlocked yes)
			(layer "F.SilkS")
			(effects
				(font
					(size 0.7874 0.5842)
					(thickness 0.1524)
				)
				(justify left)
			)
		)
		(property "Value" ""
			(at 0 0 0)
			(layer "F.Fab")
			(effects
				(font
					(size 1.27 1.27)
				)
			)
		)
		(duplicate_pad_numbers_are_jumpers no)
		(pad "113" smd rect
			(at -2.050034 36.975034 270)
			(size 0.519938 1.4986)
			(layers "F.Cu" "F.Mask" "F.Paste")
			(net "M_A_CPU1_SB_DQ<9>")
		)
		(pad "114" smd rect
			(at -2.050034 37.824918 270)
			(size 0.519938 1.4986)
			(layers "F.Cu" "F.Mask" "F.Paste")
			(net "GND")
		)
		(pad "115" smd rect
			(at -2.050034 38.675056 270)
			(size 0.519938 1.4986)
			(layers "F.Cu" "F.Mask" "F.Paste")
			(net "M_A_CPU1_SB_DQS_DP<1>")
		)
		(pad "116" smd rect
			(at -2.050034 39.52494 270)
			(size 0.519938 1.4986)
			(layers "F.Cu" "F.Mask" "F.Paste")
			(net "M_A_CPU1_SB_DQS_DN<1>")
		)
		(pad "117" smd rect
			(at -2.050034 40.375078 270)
			(size 0.519938 1.4986)
			(layers "F.Cu" "F.Mask" "F.Paste")
			(net "GND")
		)
		(pad "118" smd rect
			(at -2.050034 41.224962 270)
			(size 0.519938 1.4986)
			(layers "F.Cu" "F.Mask" "F.Paste")
			(net "M_A_CPU1_SB_DQ<12>")
		)
		(pad "119" smd rect
			(at -2.050034 42.0751 270)
			(size 0.519938 1.4986)
			(layers "F.Cu" "F.Mask" "F.Paste")
			(net "GND")
		)
		(pad "120" smd rect
			(at -2.050034 42.924984 270)
			(size 0.519938 1.4986)
			(layers "F.Cu" "F.Mask" "F.Paste")
			(net "M_A_CPU1_SB_DQ<13>")
		)
		(pad "121" smd rect
			(at -2.050034 43.775122 270)
			(size 0.519938 1.4986)
			(layers "F.Cu" "F.Mask" "F.Paste")
			(net "GND")
		)
		(pad "122" smd rect
			(at -2.050034 44.625006 270)
			(size 0.519938 1.4986)
			(layers "F.Cu" "F.Mask" "F.Paste")
			(net "M_A_CPU1_SB_DQ<16>")
		)
		(pad "123" smd rect
			(at -2.050034 45.47489 270)
			(size 0.519938 1.4986)
			(layers "F.Cu" "F.Mask" "F.Paste")
			(net "GND")
		)
		(pad "124" smd rect
			(at -2.050034 46.325028 270)
			(size 0.519938 1.4986)
			(layers "F.Cu" "F.Mask" "F.Paste")
			(net "M_A_CPU1_SB_DQ<17>")
		)
		(pad "125" smd rect
			(at -2.050034 47.174912 270)
			(size 0.519938 1.4986)
			(layers "F.Cu" "F.Mask" "F.Paste")
			(net "GND")
		)
		(pad "126" smd rect
			(at -2.050034 48.02505 270)
			(size 0.519938 1.4986)
			(layers "F.Cu" "F.Mask" "F.Paste")
			(net "M_A_CPU1_SB_DQS_DP<2>")
		)
		(pad "127" smd rect
			(at -2.050034 48.874934 270)
			(size 0.519938 1.4986)
			(layers "F.Cu" "F.Mask" "F.Paste")
			(net "M_A_CPU1_SB_DQS_DN<2>")
		)
		(pad "128" smd rect
			(at -2.050034 49.725072 270)
			(size 0.519938 1.4986)
			(layers "F.Cu" "F.Mask" "F.Paste")
			(net "GND")
		)
		(pad "129" smd rect
			(at -2.050034 50.574956 270)
			(size 0.519938 1.4986)
			(layers "F.Cu" "F.Mask" "F.Paste")
			(net "M_A_CPU1_SB_DQ<20>")
		)
		(pad "130" smd rect
			(at -2.050034 51.425094 270)
			(size 0.519938 1.4986)
			(layers "F.Cu" "F.Mask" "F.Paste")
			(net "GND")
		)
		(pad "131" smd rect
			(at -2.050034 52.274978 270)
			(size 0.519938 1.4986)
			(layers "F.Cu" "F.Mask" "F.Paste")
			(net "M_A_CPU1_SB_DQ<21>")
		)
		(pad "132" smd rect
			(at -2.050034 53.125116 270)
			(size 0.519938 1.4986)
			(layers "F.Cu" "F.Mask" "F.Paste")
			(net "GND")
		)
		(pad "133" smd rect
			(at -2.050034 53.975 270)
			(size 0.519938 1.4986)
			(layers "F.Cu" "F.Mask" "F.Paste")
			(net "M_A_CPU1_SB_DQ<24>")
		)
		(pad "134" smd rect
			(at -2.050034 54.824884 270)
			(size 0.519938 1.4986)
			(layers "F.Cu" "F.Mask" "F.Paste")
			(net "GND")
		)
		(pad "135" smd rect
			(at -2.050034 55.675022 270)
			(size 0.519938 1.4986)
			(layers "F.Cu" "F.Mask" "F.Paste")
			(net "M_A_CPU1_SB_DQ<25>")
		)
		(pad "136" smd rect
			(at -2.050034 56.524906 270)
			(size 0.519938 1.4986)
			(layers "F.Cu" "F.Mask" "F.Paste")
			(net "GND")
		)
		(pad "137" smd rect
			(at -2.050034 57.375044 270)
			(size 0.519938 1.4986)
			(layers "F.Cu" "F.Mask" "F.Paste")
			(net "M_A_CPU1_SB_DQS_DP<3>")
		)
		(pad "138" smd rect
			(at -2.050034 58.224928 270)
			(size 0.519938 1.4986)
			(layers "F.Cu" "F.Mask" "F.Paste")
			(net "M_A_CPU1_SB_DQS_DN<3>")
		)
		(pad "139" smd rect
			(at -2.050034 59.075066 270)
			(size 0.519938 1.4986)
			(layers "F.Cu" "F.Mask" "F.Paste")
			(net "GND")
		)
		(pad "140" smd rect
			(at -2.050034 59.92495 270)
			(size 0.519938 1.4986)
			(layers "F.Cu" "F.Mask" "F.Paste")
			(net "M_A_CPU1_SB_DQ<28>")
		)
		(pad "141" smd rect
			(at -2.050034 60.775088 270)
			(size 0.519938 1.4986)
			(layers "F.Cu" "F.Mask" "F.Paste")
			(net "GND")
		)
		(pad "142" smd rect
			(at -2.050034 61.624972 270)
			(size 0.519938 1.4986)
			(layers "F.Cu" "F.Mask" "F.Paste")
			(net "M_A_CPU1_SB_DQ<29>")
		)
		(pad "143" smd rect
			(at -2.050034 62.47511 270)
			(size 0.519938 1.4986)
			(layers "F.Cu" "F.Mask" "F.Paste")
			(net "GND")
		)
		(pad "144" smd rect
			(at -2.050034 63.324994 270)
			(size 0.519938 1.4986)
			(layers "F.Cu" "F.Mask" "F.Paste")
			(net "TP_CHA_CPU1_DIMM1_FRU_1")
		)
		(pad "145" smd rect
			(at 2.050034 -63.324994 270)
			(size 0.519938 1.4986)
			(layers "F.Cu" "F.Mask" "F.Paste")
			(net "P12V_S3_AUX_CPU1_NVDIMM")
		)
		(pad "146" smd rect
			(at 2.050034 -62.47511 270)
			(size 0.519938 1.4986)
			(layers "F.Cu" "F.Mask" "F.Paste")
			(net "P12V_S3_AUX_CPU1_NVDIMM")
		)
		(pad "147" smd rect
			(at 2.050034 -61.624972 270)
			(size 0.519938 1.4986)
			(layers "F.Cu" "F.Mask" "F.Paste")
			(net "PWRGD_CHA_CPU1_DIMM1")
		)
		(pad "148" smd rect
			(at 2.050034 -60.775088 270)
			(size 0.519938 1.4986)
			(layers "F.Cu" "F.Mask" "F.Paste")
			(net "PD_CHA_CPU1_DIMM1_SAA")
		)
		(pad "149" smd rect
			(at 2.050034 -59.92495 270)
			(size 0.519938 1.4986)
			(layers "F.Cu" "F.Mask" "F.Paste")
			(net "TP_CHA_CPU1_DIMM1_FRU_2")
		)
		(pad "150" smd rect
			(at 2.050034 -59.075066 270)
			(size 0.519938 1.4986)
			(layers "F.Cu" "F.Mask" "F.Paste")
			(net "TP_CHA_CPU1_DIMM1_FRU_3")
		)
		(pad "151" smd rect
			(at 2.050034 -58.224928 270)
			(size 0.519938 1.4986)
			(layers "F.Cu" "F.Mask" "F.Paste")
			(net "GND")
		)
		(pad "152" smd rect
			(at 2.050034 -57.375044 270)
			(size 0.519938 1.4986)
			(layers "F.Cu" "F.Mask" "F.Paste")
			(net "M_A_CPU1_SA_DQ<2>")
		)
		(pad "153" smd rect
			(at 2.050034 -56.524906 270)
			(size 0.519938 1.4986)
			(layers "F.Cu" "F.Mask" "F.Paste")
			(net "GND")
		)
		(pad "154" smd rect
			(at 2.050034 -55.675022 270)
			(size 0.519938 1.4986)
			(layers "F.Cu" "F.Mask" "F.Paste")
			(net "M_A_CPU1_SA_DQ<3>")
		)
		(pad "155" smd rect
			(at 2.050034 -54.824884 270)
			(size 0.519938 1.4986)
			(layers "F.Cu" "F.Mask" "F.Paste")
			(net "GND")
		)
		(pad "156" smd rect
			(at 2.050034 -53.975 270)
			(size 0.519938 1.4986)
			(layers "F.Cu" "F.Mask" "F.Paste")
			(net "M_A_CPU1_SA_DQS_DN<5>")
		)
		(pad "157" smd rect
			(at 2.050034 -53.125116 270)
			(size 0.519938 1.4986)
			(layers "F.Cu" "F.Mask" "F.Paste")
			(net "M_A_CPU1_SA_DQS_DP<5>")
		)
		(pad "158" smd rect
			(at 2.050034 -52.274978 270)
			(size 0.519938 1.4986)
			(layers "F.Cu" "F.Mask" "F.Paste")
			(net "GND")
		)
		(pad "159" smd rect
			(at 2.050034 -51.425094 270)
			(size 0.519938 1.4986)
			(layers "F.Cu" "F.Mask" "F.Paste")
			(net "M_A_CPU1_SA_DQ<6>")
		)
		(pad "160" smd rect
			(at 2.050034 -50.574956 270)
			(size 0.519938 1.4986)
			(layers "F.Cu" "F.Mask" "F.Paste")
			(net "GND")
		)
		(pad "161" smd rect
			(at 2.050034 -49.725072 270)
			(size 0.519938 1.4986)
			(layers "F.Cu" "F.Mask" "F.Paste")
			(net "M_A_CPU1_SA_DQ<7>")
		)
		(pad "162" smd rect
			(at 2.050034 -48.874934 270)
			(size 0.519938 1.4986)
			(layers "F.Cu" "F.Mask" "F.Paste")
			(net "GND")
		)
		(pad "163" smd rect
			(at 2.050034 -48.02505 270)
			(size 0.519938 1.4986)
			(layers "F.Cu" "F.Mask" "F.Paste")
			(net "M_A_CPU1_SA_DQ<10>")
		)
		(pad "164" smd rect
			(at 2.050034 -47.174912 270)
			(size 0.519938 1.4986)
			(layers "F.Cu" "F.Mask" "F.Paste")
			(net "GND")
		)
		(pad "165" smd rect
			(at 2.050034 -46.325028 270)
			(size 0.519938 1.4986)
			(layers "F.Cu" "F.Mask" "F.Paste")
			(net "M_A_CPU1_SA_DQ<11>")
		)
		(pad "166" smd rect
			(at 2.050034 -45.47489 270)
			(size 0.519938 1.4986)
			(layers "F.Cu" "F.Mask" "F.Paste")
			(net "GND")
		)
		(pad "167" smd rect
			(at 2.050034 -44.625006 270)
			(size 0.519938 1.4986)
			(layers "F.Cu" "F.Mask" "F.Paste")
			(net "M_A_CPU1_SA_DQS_DN<6>")
		)
		(pad "168" smd rect
			(at 2.050034 -43.775122 270)
			(size 0.519938 1.4986)
			(layers "F.Cu" "F.Mask" "F.Paste")
			(net "M_A_CPU1_SA_DQS_DP<6>")
		)
		(pad "169" smd rect
			(at 2.050034 -42.924984 270)
			(size 0.519938 1.4986)
			(layers "F.Cu" "F.Mask" "F.Paste")
			(net "GND")
		)
		(pad "170" smd rect
			(at 2.050034 -42.0751 270)
			(size 0.519938 1.4986)
			(layers "F.Cu" "F.Mask" "F.Paste")
			(net "M_A_CPU1_SA_DQ<14>")
		)
		(pad "171" smd rect
			(at 2.050034 -41.224962 270)
			(size 0.519938 1.4986)
			(layers "F.Cu" "F.Mask" "F.Paste")
			(net "GND")
		)
		(pad "172" smd rect
			(at 2.050034 -40.375078 270)
			(size 0.519938 1.4986)
			(layers "F.Cu" "F.Mask" "F.Paste")
			(net "M_A_CPU1_SA_DQ<15>")
		)
		(pad "173" smd rect
			(at 2.050034 -39.52494 270)
			(size 0.519938 1.4986)
			(layers "F.Cu" "F.Mask" "F.Paste")
			(net "GND")
		)
		(pad "174" smd rect
			(at 2.050034 -38.675056 270)
			(size 0.519938 1.4986)
			(layers "F.Cu" "F.Mask" "F.Paste")
			(net "M_A_CPU1_SA_DQ<18>")
		)
		(pad "175" smd rect
			(at 2.050034 -37.824918 270)
			(size 0.519938 1.4986)
			(layers "F.Cu" "F.Mask" "F.Paste")
			(net "GND")
		)
		(pad "176" smd rect
			(at 2.050034 -36.975034 270)
			(size 0.519938 1.4986)
			(layers "F.Cu" "F.Mask" "F.Paste")
			(net "M_A_CPU1_SA_DQ<19>")
		)
		(pad "177" smd rect
			(at 2.050034 -36.124896 270)
			(size 0.519938 1.4986)
			(layers "F.Cu" "F.Mask" "F.Paste")
			(net "GND")
		)
		(pad "178" smd rect
			(at 2.050034 -35.275012 270)
			(size 0.519938 1.4986)
			(layers "F.Cu" "F.Mask" "F.Paste")
			(net "M_A_CPU1_SA_DQS_DN<7>")
		)
		(pad "179" smd rect
			(at 2.050034 -34.425128 270)
			(size 0.519938 1.4986)
			(layers "F.Cu" "F.Mask" "F.Paste")
			(net "M_A_CPU1_SA_DQS_DP<7>")
		)
		(pad "180" smd rect
			(at 2.050034 -33.57499 270)
			(size 0.519938 1.4986)
			(layers "F.Cu" "F.Mask" "F.Paste")
			(net "GND")
		)
		(pad "181" smd rect
			(at 2.050034 -32.725106 270)
			(size 0.519938 1.4986)
			(layers "F.Cu" "F.Mask" "F.Paste")
			(net "M_A_CPU1_SA_DQ<22>")
		)
		(pad "182" smd rect
			(at 2.050034 -31.874968 270)
			(size 0.519938 1.4986)
			(layers "F.Cu" "F.Mask" "F.Paste")
			(net "GND")
		)
		(pad "183" smd rect
			(at 2.050034 -31.025084 270)
			(size 0.519938 1.4986)
			(layers "F.Cu" "F.Mask" "F.Paste")
			(net "M_A_CPU1_SA_DQ<23>")
		)
		(pad "184" smd rect
			(at 2.050034 -30.174946 270)
			(size 0.519938 1.4986)
			(layers "F.Cu" "F.Mask" "F.Paste")
			(net "GND")
		)
		(pad "185" smd rect
			(at 2.050034 -29.325062 270)
			(size 0.519938 1.4986)
			(layers "F.Cu" "F.Mask" "F.Paste")
			(net "M_A_CPU1_SA_DQ<26>")
		)
		(pad "186" smd rect
			(at 2.050034 -28.474924 270)
			(size 0.519938 1.4986)
			(layers "F.Cu" "F.Mask" "F.Paste")
			(net "GND")
		)
		(pad "187" smd rect
			(at 2.050034 -27.62504 270)
			(size 0.519938 1.4986)
			(layers "F.Cu" "F.Mask" "F.Paste")
			(net "M_A_CPU1_SA_DQ<27>")
		)
		(pad "188" smd rect
			(at 2.050034 -26.774902 270)
			(size 0.519938 1.4986)
			(layers "F.Cu" "F.Mask" "F.Paste")
			(net "GND")
		)
		(pad "189" smd rect
			(at 2.050034 -25.925018 270)
			(size 0.519938 1.4986)
			(layers "F.Cu" "F.Mask" "F.Paste")
			(net "M_A_CPU1_SA_DQS_DN<8>")
		)
		(pad "190" smd rect
			(at 2.050034 -25.07488 270)
			(size 0.519938 1.4986)
			(layers "F.Cu" "F.Mask" "F.Paste")
			(net "M_A_CPU1_SA_DQS_DP<8>")
		)
		(pad "191" smd rect
			(at 2.050034 -24.224996 270)
			(size 0.519938 1.4986)
			(layers "F.Cu" "F.Mask" "F.Paste")
			(net "GND")
		)
		(pad "192" smd rect
			(at 2.050034 -23.375112 270)
			(size 0.519938 1.4986)
			(layers "F.Cu" "F.Mask" "F.Paste")
			(net "M_A_CPU1_SA_DQ<30>")
		)
		(pad "193" smd rect
			(at 2.050034 -22.524974 270)
			(size 0.519938 1.4986)
			(layers "F.Cu" "F.Mask" "F.Paste")
			(net "GND")
		)
		(pad "194" smd rect
			(at 2.050034 -21.67509 270)
			(size 0.519938 1.4986)
			(layers "F.Cu" "F.Mask" "F.Paste")
			(net "M_A_CPU1_SA_DQ<31>")
		)
		(pad "195" smd rect
			(at 2.050034 -20.824952 270)
			(size 0.519938 1.4986)
			(layers "F.Cu" "F.Mask" "F.Paste")
			(net "GND")
		)
		(pad "196" smd rect
			(at 2.050034 -19.975068 270)
			(size 0.519938 1.4986)
			(layers "F.Cu" "F.Mask" "F.Paste")
			(net "M_A_CPU1_SA_CB<2>")
		)
		(pad "197" smd rect
			(at 2.050034 -19.12493 270)
			(size 0.519938 1.4986)
			(layers "F.Cu" "F.Mask" "F.Paste")
			(net "GND")
		)
		(pad "198" smd rect
			(at 2.050034 -18.275046 270)
			(size 0.519938 1.4986)
			(layers "F.Cu" "F.Mask" "F.Paste")
			(net "M_A_CPU1_SA_CB<3>")
		)
		(pad "199" smd rect
			(at 2.050034 -17.424908 270)
			(size 0.519938 1.4986)
			(layers "F.Cu" "F.Mask" "F.Paste")
			(net "GND")
		)
		(pad "200" smd rect
			(at 2.050034 -16.575024 270)
			(size 0.519938 1.4986)
			(layers "F.Cu" "F.Mask" "F.Paste")
			(net "M_A_CPU1_SA_DQS_DN<9>")
		)
		(pad "201" smd rect
			(at 2.050034 -15.724886 270)
			(size 0.519938 1.4986)
			(layers "F.Cu" "F.Mask" "F.Paste")
			(net "M_A_CPU1_SA_DQS_DP<9>")
		)
		(pad "202" smd rect
			(at 2.050034 -14.875002 270)
			(size 0.519938 1.4986)
			(layers "F.Cu" "F.Mask" "F.Paste")
			(net "GND")
		)
		(pad "203" smd rect
			(at 2.050034 -14.025118 270)
			(size 0.519938 1.4986)
			(layers "F.Cu" "F.Mask" "F.Paste")
			(net "M_A_CPU1_SA_CB<6>")
		)
		(pad "204" smd rect
			(at 2.050034 -13.17498 270)
			(size 0.519938 1.4986)
			(layers "F.Cu" "F.Mask" "F.Paste")
			(net "GND")
		)
		(pad "205" smd rect
			(at 2.050034 -12.325096 270)
			(size 0.519938 1.4986)
			(layers "F.Cu" "F.Mask" "F.Paste")
			(net "M_A_CPU1_SA_CB<7>")
		)
		(pad "206" smd rect
			(at 2.050034 -11.474958 270)
			(size 0.519938 1.4986)
			(layers "F.Cu" "F.Mask" "F.Paste")
			(net "GND")
		)
		(pad "207" smd rect
			(at 2.050034 -10.625074 270)
			(size 0.519938 1.4986)
			(layers "F.Cu" "F.Mask" "F.Paste")
			(net "RST_M_AB_CPU1_FPGA_N")
		)
		(pad "208" smd rect
			(at 2.050034 -9.774936 270)
			(size 0.519938 1.4986)
			(layers "F.Cu" "F.Mask" "F.Paste")
			(net "GND")
		)
		(pad "209" smd rect
			(at 2.050034 -8.925052 270)
			(size 0.519938 1.4986)
			(layers "F.Cu" "F.Mask" "F.Paste")
			(net "M_A_CPU1_SA_CS_N<1>")
		)
		(pad "210" smd rect
			(at 2.050034 -8.074914 270)
			(size 0.519938 1.4986)
			(layers "F.Cu" "F.Mask" "F.Paste")
			(net "GND")
		)
		(pad "211" smd rect
			(at 2.050034 -7.22503 270)
			(size 0.519938 1.4986)
			(layers "F.Cu" "F.Mask" "F.Paste")
			(net "M_A_CPU1_SA_CA<1>")
		)
		(pad "212" smd rect
			(at 2.050034 -6.374892 270)
			(size 0.519938 1.4986)
			(layers "F.Cu" "F.Mask" "F.Paste")
			(net "GND")
		)
		(pad "213" smd rect
			(at 2.050034 -5.525008 270)
			(size 0.519938 1.4986)
			(layers "F.Cu" "F.Mask" "F.Paste")
			(net "M_A_CPU1_SA_CA<3>")
		)
		(pad "214" smd rect
			(at 2.050034 -4.675124 270)
			(size 0.519938 1.4986)
			(layers "F.Cu" "F.Mask" "F.Paste")
			(net "GND")
		)
		(pad "215" smd rect
			(at 2.050034 -3.824986 270)
			(size 0.519938 1.4986)
			(layers "F.Cu" "F.Mask" "F.Paste")
			(net "M_A_CPU1_SA_CA<5>")
		)
		(pad "216" smd rect
			(at 2.050034 -2.975102 270)
			(size 0.519938 1.4986)
			(layers "F.Cu" "F.Mask" "F.Paste")
			(net "GND")
		)
		(pad "217" smd rect
			(at 2.050034 -2.124964 270)
			(size 0.519938 1.4986)
			(layers "F.Cu" "F.Mask" "F.Paste")
			(net "M_A_CPU1_CLK_DP<0>")
		)
		(pad "218" smd rect
			(at 2.050034 -1.27508 270)
			(size 0.519938 1.4986)
			(layers "F.Cu" "F.Mask" "F.Paste")
			(net "M_A_CPU1_CLK_DN<0>")
		)
		(pad "219" smd rect
			(at 2.050034 -0.424942 270)
			(size 0.519938 1.4986)
			(layers "F.Cu" "F.Mask" "F.Paste")
			(net "GND")
		)
		(pad "220" smd rect
			(at 2.050034 5.525008 270)
			(size 0.519938 1.4986)
			(layers "F.Cu" "F.Mask" "F.Paste")
			(net "TP_CHA_CPU1_DIMM1_FRU_4")
		)
		(pad "221" smd rect
			(at 2.050034 6.374892 270)
			(size 0.519938 1.4986)
			(layers "F.Cu" "F.Mask" "F.Paste")
			(net "M_A_CPU1_SB_CA<1>")
		)
		(pad "222" smd rect
			(at 2.050034 7.22503 270)
			(size 0.519938 1.4986)
			(layers "F.Cu" "F.Mask" "F.Paste")
			(net "GND")
		)
		(pad "223" smd rect
			(at 2.050034 8.074914 270)
			(size 0.519938 1.4986)
			(layers "F.Cu" "F.Mask" "F.Paste")
			(net "M_A_CPU1_SB_CA<3>")
		)
		(pad "224" smd rect
			(at 2.050034 8.925052 270)
			(size 0.519938 1.4986)
			(layers "F.Cu" "F.Mask" "F.Paste")
			(net "GND")
		)
	)
)
